# TIMECARD (Time Appliance Project (Time Card)) — schematic netlist excerpt (pin names and nets, part order shuffled) for the footprints in the layout excerpt that follows; sources: Cadence DE-HDL packaged netlist, KiCad conversion of R4006-B0001-02_R01.brd

R226  RESISTOR  330OHM 1%  pkg SMC_0402R_H016  page 31 : \1\ = XP1R8V_FPGA_PG ; \2\ = XP3R3V_FPGA_EN_R
R338  RESISTOR  1KOHM 1%  pkg SMC_0402R_H016  page 17 : \1\ = UNNAMED_6_LM75BDPTSSOP8_I34_A0 ; \2\ = SG

(kicad_pcb
	(version 20260206)
	(generator "pcbnew")
	(generator_version "10.0")
	(general
		(thickness 1.6)
		(legacy_teardrops no)
	)
	(paper "A4")
	(title_block
		(title "timecard-production-celestica-r4006 — R4006-B0001-02_R01.brd")
		(comment 1 "Time Appliance Project (Time Card) / footprints 968-969 of 1113")
	)
	(layers
		(0 "F.Cu" signal "TOP")
		(4 "In1.Cu" signal "L02_GND1")
		(6 "In2.Cu" signal "L03_SIG1")
		(8 "In3.Cu" signal "L04_GND2")
		(10 "In4.Cu" signal "L05_VCC1")
		(12 "In5.Cu" signal "L06_VCC2")
		(14 "In6.Cu" signal "L07_GND3")
		(16 "In7.Cu" signal "L08_SIG2")
		(18 "In8.Cu" signal "L09_GND4")
		(2 "B.Cu" signal "BOTTOM")
		(9 "F.Adhes" user "F.Adhesive")
		(11 "B.Adhes" user "B.Adhesive")
		(13 "F.Paste" user "Package Geometry/Pastemask Top")
		(15 "B.Paste" user "Package Geometry/Pastemask Bottom")
		(5 "F.SilkS" user "Ref Des/Silkscreen Top")
		(7 "B.SilkS" user "Ref Des/Silkscreen Bottom")
		(1 "F.Mask" user "Board Geometry/Soldermask Top")
		(3 "B.Mask" user "Board Geometry/Soldermask Bottom")
		(17 "Dwgs.User" user "User.Drawings")
		(19 "Cmts.User" user "User.Comments")
		(21 "Eco1.User" user "User.Eco1")
		(23 "Eco2.User" user "User.Eco2")
		(25 "Edge.Cuts" user "Board Geometry/Outline")
		(27 "Margin" user)
		(31 "F.CrtYd" user "Package Geometry/Place Bound Top")
		(29 "B.CrtYd" user "Package Geometry/Place Bound Bottom")
		(35 "F.Fab" user "Ref Des/Assembly Top")
		(33 "B.Fab" user "Ref Des/Assembly Bottom")
	)
	(footprint ""
		(layer "B.Cu")
		(at 5.588 -76.835)
		(property "Reference" "R338"
			(at -3.048 -0.46863 0)
			(unlocked yes)
			(layer "B.SilkS")
			(effects
				(font
					(size 0.7874 0.5842)
					(thickness 0.1524)
				)
				(justify mirror)
			)
		)
		(property "Value" "VAL*"
			(at -0.02032 2.13233 0)
			(unlocked yes)
			(layer "B.Fab")
			(hide yes)
			(effects
				(font
					(size 0.7874 0.5842)
					(thickness 0.1524)
				)
				(justify mirror)
			)
		)
		(property "Tolerance" "TOL*"
			(at -0.044704 3.05435 0)
			(unlocked yes)
			(layer "Cmts.User")
			(hide yes)
			(effects
				(font
					(size 0.7874 0.5842)
					(thickness 0.1524)
				)
				(justify mirror)
			)
		)
		(property "User Part Number" "PARTNUM*"
			(at -0.02032 4.024884 0)
			(unlocked yes)
			(layer "Cmts.User")
			(hide yes)
			(effects
				(font
					(size 0.7874 0.5842)
					(thickness 0.1524)
				)
				(justify mirror)
			)
		)
		(property "Device Type" "RESISTOR-G155-11001-01,1KOHM,1%"
			(at -0.008382 1.210564 0)
			(unlocked yes)
			(layer "B.Fab")
			(hide yes)
			(effects
				(font
					(size 0.7874 0.5842)
					(thickness 0.1524)
				)
				(justify mirror)
			)
		)
		(duplicate_pad_numbers_are_jumpers no)
		(fp_line
			(start -1.143 -0.5588)
			(end 1.143 -0.5588)
			(stroke
				(width 0.1)
				(type default)
			)
			(layer "B.SilkS")
		)
		(fp_line
			(start -1.143 0.5588)
			(end -1.143 -0.5588)
			(stroke
				(width 0.1)
				(type default)
			)
			(layer "B.SilkS")
		)
		(fp_line
			(start 1.143 -0.5588)
			(end 1.143 0.5588)
			(stroke
				(width 0.1)
				(type default)
			)
			(layer "B.SilkS")
		)
		(fp_line
			(start 1.143 0.5588)
			(end -1.143 0.5588)
			(stroke
				(width 0.1)
				(type default)
			)
			(layer "B.SilkS")
		)
		(fp_rect
			(start 1.143 0.5588)
			(end -1.143 -0.5588)
			(stroke
				(width 0)
				(type default)
			)
			(fill no)
			(layer "B.CrtYd")
		)
		(fp_line
			(start -0.508 -0.3048)
			(end 0.508 -0.3048)
			(stroke
				(width 0.1)
				(type default)
			)
			(layer "B.Fab")
		)
		(fp_line
			(start -0.508 0.3048)
			(end -0.508 -0.3048)
			(stroke
				(width 0.1)
				(type default)
			)
			(layer "B.Fab")
		)
		(fp_line
			(start 0.508 -0.3048)
			(end 0.508 0.3048)
			(stroke
				(width 0.1)
				(type default)
			)
			(layer "B.Fab")
		)
		(fp_line
			(start 0.508 0.3048)
			(end -0.508 0.3048)
			(stroke
				(width 0.1)
				(type default)
			)
			(layer "B.Fab")
		)
		(pad "1" smd rect
			(at 0.5334 0 180)
			(size 0.7112 0.6096)
			(layers "B.Cu" "B.Mask" "B.Paste")
			(net "UNNAMED_6_LM75BDPTSSOP8_I34_A0")
		)
		(pad "2" smd rect
			(at -0.5334 0 180)
			(size 0.7112 0.6096)
			(layers "B.Cu" "B.Mask" "B.Paste")
			(net "SG")
		)
		(zone
			(layer "B.Cu")
			(hatch none 0.5)
			(connect_pads
				(clearance 0)
			)
			(min_thickness 0.25)
			(keepout
				(tracks allowed)
				(vias not_allowed)
				(pads allowed)
				(copperpour not_allowed)
				(footprints allowed)
			)
			(placement
				(enabled no)
				(sheetname "")
			)
			(fill
				(thermal_gap 0.5)
				(thermal_bridge_width 0.5)
				(island_removal_mode 0)
			)
			(polygon
				(pts
					(xy 5.6642 -76.5302) (xy 5.6642 -77.1398) (xy 5.5118 -77.1398) (xy 5.5118 -76.5302)
				)
			)
		)
	)
	(footprint ""
		(layer "B.Cu")
		(at 115.443 -74.803)
		(property "Reference" "R226"
			(at -0.127 -2.11963 0)
			(unlocked yes)
			(layer "B.SilkS")
			(effects
				(font
					(size 0.7874 0.5842)
					(thickness 0.1524)
				)
				(justify mirror)
			)
		)
		(property "Value" "VAL*"
			(at -0.02032 2.13233 0)
			(unlocked yes)
			(layer "B.Fab")
			(hide yes)
			(effects
				(font
					(size 0.7874 0.5842)
					(thickness 0.1524)
				)
				(justify mirror)
			)
		)
		(property "Device Type" "RESISTOR-G155-13300-01,330OHM,A"
			(at -0.008382 1.210564 0)
			(unlocked yes)
			(layer "B.Fab")
			(hide yes)
			(effects
				(font
					(size 0.7874 0.5842)
					(thickness 0.1524)
				)
				(justify mirror)
			)
		)
		(property "User Part Number" "PARTNUM*"
			(at -0.02032 4.024884 0)
			(unlocked yes)
			(layer "Cmts.User")
			(hide yes)
			(effects
				(font
					(size 0.7874 0.5842)
					(thickness 0.1524)
				)
				(justify mirror)
			)
		)
		(property "Tolerance" "TOL*"
			(at -0.044704 3.05435 0)
			(unlocked yes)
			(layer "Cmts.User")
			(hide yes)
			(effects
				(font
					(size 0.7874 0.5842)
					(thickness 0.1524)
				)
				(justify mirror)
			)
		)
		(duplicate_pad_numbers_are_jumpers no)
		(fp_line
			(start -1.143 -0.5588)
			(end 1.143 -0.5588)
			(stroke
				(width 0.1)
				(type default)
			)
			(layer "B.SilkS")
		)
		(fp_line
			(start -1.143 0.5588)
			(end -1.143 -0.5588)
			(stroke
				(width 0.1)
				(type default)
			)
			(layer "B.SilkS")
		)
		(fp_line
			(start 1.143 -0.5588)
			(end 1.143 0.5588)
			(stroke
				(width 0.1)
				(type default)
			)
			(layer "B.SilkS")
		)
		(fp_line
			(start 1.143 0.5588)
			(end -1.143 0.5588)
			(stroke
				(width 0.1)
				(type default)
			)
			(layer "B.SilkS")
		)
		(fp_rect
			(start -1.143 0.5588)
			(end 1.143 -0.5588)
			(stroke
				(width 0)
				(type default)
			)
			(fill no)
			(layer "B.CrtYd")
		)
		(fp_line
			(start -0.508 -0.3048)
			(end 0.508 -0.3048)
			(stroke
				(width 0.1)
				(type default)
			)
			(layer "B.Fab")
		)
		(fp_line
			(start -0.508 0.3048)
			(end -0.508 -0.3048)
			(stroke
				(width 0.1)
				(type default)
			)
			(layer "B.Fab")
		)
		(fp_line
			(start 0.508 -0.3048)
			(end 0.508 0.3048)
			(stroke
				(width 0.1)
				(type default)
			)
			(layer "B.Fab")
		)
		(fp_line
			(start 0.508 0.3048)
			(end -0.508 0.3048)
			(stroke
				(width 0.1)
				(type default)
			)
			(layer "B.Fab")
		)
		(pad "1" smd rect
			(at 0.5334 0 180)
			(size 0.7112 0.6096)
			(layers "B.Cu" "B.Mask" "B.Paste")
			(net "XP1R8V_FPGA_PG")
		)
		(pad "2" smd rect
			(at -0.5334 0 180)
			(size 0.7112 0.6096)
			(layers "B.Cu" "B.Mask" "B.Paste")
			(net "XP3R3V_FPGA_EN_R")
		)
		(zone
			(layer "B.Cu")
			(hatch none 0.5)
			(connect_pads
				(clearance 0)
			)
			(min_thickness 0.25)
			(keepout
				(tracks allowed)
				(vias not_allowed)
				(pads allowed)
				(copperpour not_allowed)
				(footprints allowed)
			)
			(placement
				(enabled no)
				(sheetname "")
			)
			(fill
				(thermal_gap 0.5)
				(thermal_bridge_width 0.5)
				(island_removal_mode 0)
			)
			(polygon
				(pts
					(xy 115.3668 -74.4982) (xy 115.5192 -74.4982) (xy 115.5192 -75.1078) (xy 115.3668 -75.1078)
				)
			)
		)
	)
)
